# BASEBOARD_FAB2 (Tioga Pass) — schematic netlist excerpt (pin names and nets, part order shuffled) for the footprints in the layout excerpt that follows; sources: Cadence DE-HDL packaged netlist, KiCad conversion of Wiwynn_Tioga_Pass_MB.brd

R8P3  RES  49.9 1% CHIP  pkg 0402  page 56 : A = PD_CPU1_RSVD_TEST_2 ; B = GND
R3U2  RES  100.0 1% CHIP  pkg 0402  page 215 : A = PVCCIO_CPU0 ; B = SVID_DIO1_CPU0_R
R2T68  RES  0.0 5% CHIP  pkg 0402  page 93 : A = H_CPU1_PROCHOT_G_N ; B = H_CPU1_PROCHOT_G_R_N

(kicad_pcb
	(version 20260206)
	(generator "pcbnew")
	(generator_version "10.0")
	(general
		(thickness 1.6)
		(legacy_teardrops no)
	)
	(paper "A4")
	(title_block
		(title "Wiwynn_Tioga_Pass_MB.brd")
		(comment 1 "Tioga Pass / footprints 3637-3639 of 4770")
	)
	(layers
		(0 "F.Cu" signal "TOP")
		(4 "In1.Cu" signal "L2GND")
		(6 "In2.Cu" signal "L3")
		(8 "In3.Cu" signal "L4GND")
		(10 "In4.Cu" signal "L5")
		(12 "In5.Cu" signal "L6GND")
		(14 "In6.Cu" signal "L7VCC")
		(16 "In7.Cu" signal "L8VCC")
		(18 "In8.Cu" signal "L9GND")
		(20 "In9.Cu" signal "L10")
		(22 "In10.Cu" signal "L11GND")
		(24 "In11.Cu" signal "L12")
		(26 "In12.Cu" signal "L13GND")
		(2 "B.Cu" signal "BOTTOM")
		(9 "F.Adhes" user "F.Adhesive")
		(11 "B.Adhes" user "B.Adhesive")
		(13 "F.Paste" user "Package Geometry/Pastemask Top")
		(15 "B.Paste" user "Package Geometry/Pastemask Bottom")
		(5 "F.SilkS" user "Ref Des/Silkscreen Top")
		(7 "B.SilkS" user "Ref Des/Silkscreen Bottom")
		(1 "F.Mask" user "Board Geometry/Soldermask Top")
		(3 "B.Mask" user "Board Geometry/Soldermask Bottom")
		(17 "Dwgs.User" user "User.Drawings")
		(19 "Cmts.User" user "User.Comments")
		(21 "Eco1.User" user "User.Eco1")
		(23 "Eco2.User" user "User.Eco2")
		(25 "Edge.Cuts" user "Board Geometry/Outline")
		(27 "Margin" user)
		(31 "F.CrtYd" user "Package Geometry/Place Bound Top")
		(29 "B.CrtYd" user "Package Geometry/Place Bound Bottom")
		(35 "F.Fab" user "Ref Des/Assembly Top")
		(33 "B.Fab" user "Ref Des/Assembly Bottom")
	)
	(footprint ""
		(layer "B.Cu")
		(at 372.169436 -47.436532)
		(property "Reference" "R2T68"
			(at 0 0 0)
			(layer "B.SilkS")
			(hide yes)
			(effects
				(font
					(size 1.27 1.27)
				)
				(justify mirror)
			)
		)
		(property "Value" ""
			(at 0 0 0)
			(layer "B.Fab")
			(effects
				(font
					(size 1.27 1.27)
				)
				(justify mirror)
			)
		)
		(duplicate_pad_numbers_are_jumpers no)
		(fp_poly
			(pts
				(xy 0.2794 -0.1016) (xy -0.2794 -0.1016) (xy -0.2794 0.9906) (xy 0.2794 0.9906)
			)
			(stroke
				(width 0)
				(type default)
			)
			(fill no)
			(layer "B.CrtYd")
		)
		(fp_line
			(start -0.2794 -0.1016)
			(end 0.2794 -0.1016)
			(stroke
				(width 0.1)
				(type default)
			)
			(layer "B.Fab")
		)
		(fp_line
			(start -0.2794 0.9906)
			(end -0.2794 -0.1016)
			(stroke
				(width 0.1)
				(type default)
			)
			(layer "B.Fab")
		)
		(fp_line
			(start 0.2794 -0.1016)
			(end 0.2794 0.9906)
			(stroke
				(width 0.1)
				(type default)
			)
			(layer "B.Fab")
		)
		(fp_line
			(start 0.2794 0.9906)
			(end -0.2794 0.9906)
			(stroke
				(width 0.1)
				(type default)
			)
			(layer "B.Fab")
		)
		(pad "1" smd rect
			(at 0 0 180)
			(size 0.508 0.508)
			(layers "B.Cu" "B.Mask" "B.Paste")
			(net "H_CPU1_PROCHOT_G_N")
		)
		(pad "2" smd rect
			(at 0 0.889 180)
			(size 0.508 0.508)
			(layers "B.Cu" "B.Mask" "B.Paste")
			(net "H_CPU1_PROCHOT_G_R_N")
		)
		(zone
			(layer "B.Cu")
			(hatch none 0.5)
			(connect_pads
				(clearance 0)
			)
			(min_thickness 0.25)
			(keepout
				(tracks allowed)
				(vias not_allowed)
				(pads allowed)
				(copperpour not_allowed)
				(footprints allowed)
			)
			(placement
				(enabled no)
				(sheetname "")
			)
			(fill
				(thermal_gap 0.5)
				(thermal_bridge_width 0.5)
				(island_removal_mode 0)
			)
			(polygon
				(pts
					(xy 372.423436 -47.182532) (xy 371.915436 -47.182532) (xy 371.915436 -46.801532) (xy 372.423436 -46.801532)
				)
			)
		)
		(zone
			(layer "B.Cu")
			(hatch none 0.5)
			(connect_pads
				(clearance 0)
			)
			(min_thickness 0.25)
			(keepout
				(tracks not_allowed)
				(vias allowed)
				(pads allowed)
				(copperpour not_allowed)
				(footprints allowed)
			)
			(placement
				(enabled no)
				(sheetname "")
			)
			(fill
				(thermal_gap 0.5)
				(thermal_bridge_width 0.5)
				(island_removal_mode 0)
			)
			(polygon
				(pts
					(xy 372.423436 -46.801532) (xy 371.915436 -46.801532) (xy 371.915436 -47.182532) (xy 372.423436 -47.182532)
				)
			)
		)
	)
	(footprint ""
		(layer "B.Cu")
		(at 338.7344 -17.272 -90)
		(property "Reference" "R3U2"
			(at 0 0 90)
			(layer "B.SilkS")
			(hide yes)
			(effects
				(font
					(size 1.27 1.27)
				)
				(justify mirror)
			)
		)
		(property "Value" ""
			(at 0 0 90)
			(layer "B.Fab")
			(effects
				(font
					(size 1.27 1.27)
				)
				(justify mirror)
			)
		)
		(duplicate_pad_numbers_are_jumpers no)
		(fp_rect
			(start 0.2794 0.9906)
			(end -0.2794 -0.1016)
			(stroke
				(width 0)
				(type default)
			)
			(fill no)
			(layer "B.CrtYd")
		)
		(fp_line
			(start -0.2794 0.9906)
			(end -0.2794 -0.1016)
			(stroke
				(width 0.1)
				(type default)
			)
			(layer "B.Fab")
		)
		(fp_line
			(start 0.2794 0.9906)
			(end -0.2794 0.9906)
			(stroke
				(width 0.1)
				(type default)
			)
			(layer "B.Fab")
		)
		(fp_line
			(start -0.2794 -0.1016)
			(end 0.2794 -0.1016)
			(stroke
				(width 0.1)
				(type default)
			)
			(layer "B.Fab")
		)
		(fp_line
			(start 0.2794 -0.1016)
			(end 0.2794 0.9906)
			(stroke
				(width 0.1)
				(type default)
			)
			(layer "B.Fab")
		)
		(pad "1" smd rect
			(at 0 0 90)
			(size 0.508 0.508)
			(layers "B.Cu" "B.Mask" "B.Paste")
			(net "PVCCIO_CPU0")
		)
		(pad "2" smd rect
			(at 0 0.889 90)
			(size 0.508 0.508)
			(layers "B.Cu" "B.Mask" "B.Paste")
			(net "SVID_DIO1_CPU0_R")
		)
		(zone
			(layer "B.Cu")
			(hatch none 0.5)
			(connect_pads
				(clearance 0)
			)
			(min_thickness 0.25)
			(keepout
				(tracks not_allowed)
				(vias allowed)
				(pads allowed)
				(copperpour not_allowed)
				(footprints allowed)
			)
			(placement
				(enabled no)
				(sheetname "")
			)
			(fill
				(thermal_gap 0.5)
				(thermal_bridge_width 0.5)
				(island_removal_mode 0)
			)
			(polygon
				(pts
					(xy 338.0994 -17.018) (xy 338.4804 -17.018) (xy 338.4804 -17.526) (xy 338.0994 -17.526)
				)
			)
		)
		(zone
			(layer "B.Cu")
			(hatch none 0.5)
			(connect_pads
				(clearance 0)
			)
			(min_thickness 0.25)
			(keepout
				(tracks allowed)
				(vias not_allowed)
				(pads allowed)
				(copperpour not_allowed)
				(footprints allowed)
			)
			(placement
				(enabled no)
				(sheetname "")
			)
			(fill
				(thermal_gap 0.5)
				(thermal_bridge_width 0.5)
				(island_removal_mode 0)
			)
			(polygon
				(pts
					(xy 338.0994 -17.018) (xy 338.4804 -17.018) (xy 338.4804 -17.526) (xy 338.0994 -17.526)
				)
			)
		)
	)
	(footprint ""
		(layer "B.Cu")
		(at 80.391 -65.151 -90)
		(property "Reference" "R8P3"
			(at 0 0 90)
			(layer "B.SilkS")
			(hide yes)
			(effects
				(font
					(size 1.27 1.27)
				)
				(justify mirror)
			)
		)
		(property "Value" ""
			(at 0 0 90)
			(layer "B.Fab")
			(effects
				(font
					(size 1.27 1.27)
				)
				(justify mirror)
			)
		)
		(duplicate_pad_numbers_are_jumpers no)
		(fp_poly
			(pts
				(xy 0.2794 -0.1016) (xy -0.2794 -0.1016) (xy -0.2794 0.9906) (xy 0.2794 0.9906)
			)
			(stroke
				(width 0)
				(type default)
			)
			(fill no)
			(layer "B.CrtYd")
		)
		(fp_line
			(start -0.2794 0.9906)
			(end -0.2794 -0.1016)
			(stroke
				(width 0.1)
				(type default)
			)
			(layer "B.Fab")
		)
		(fp_line
			(start 0.2794 0.9906)
			(end -0.2794 0.9906)
			(stroke
				(width 0.1)
				(type default)
			)
			(layer "B.Fab")
		)
		(fp_line
			(start -0.2794 -0.1016)
			(end 0.2794 -0.1016)
			(stroke
				(width 0.1)
				(type default)
			)
			(layer "B.Fab")
		)
		(fp_line
			(start 0.2794 -0.1016)
			(end 0.2794 0.9906)
			(stroke
				(width 0.1)
				(type default)
			)
			(layer "B.Fab")
		)
		(pad "1" smd rect
			(at 0 0 90)
			(size 0.508 0.508)
			(layers "B.Cu" "B.Mask" "B.Paste")
			(net "PD_CPU1_RSVD_TEST_2")
		)
		(pad "2" smd rect
			(at 0 0.889 90)
			(size 0.508 0.508)
			(layers "B.Cu" "B.Mask" "B.Paste")
			(net "GND")
		)
		(zone
			(layer "B.Cu")
			(hatch none 0.5)
			(connect_pads
				(clearance 0)
			)
			(min_thickness 0.25)
			(keepout
				(tracks not_allowed)
				(vias allowed)
				(pads allowed)
				(copperpour not_allowed)
				(footprints allowed)
			)
			(placement
				(enabled no)
				(sheetname "")
			)
			(fill
				(thermal_gap 0.5)
				(thermal_bridge_width 0.5)
				(island_removal_mode 0)
			)
			(polygon
				(pts
					(xy 79.756 -64.897) (xy 79.756 -65.405) (xy 80.137 -65.405) (xy 80.137 -64.897)
				)
			)
		)
		(zone
			(layer "B.Cu")
			(hatch none 0.5)
			(connect_pads
				(clearance 0)
			)
			(min_thickness 0.25)
			(keepout
				(tracks allowed)
				(vias not_allowed)
				(pads allowed)
				(copperpour not_allowed)
				(footprints allowed)
			)
			(placement
				(enabled no)
				(sheetname "")
			)
			(fill
				(thermal_gap 0.5)
				(thermal_bridge_width 0.5)
				(island_removal_mode 0)
			)
			(polygon
				(pts
					(xy 80.137 -64.897) (xy 80.137 -65.405) (xy 79.756 -65.405) (xy 79.756 -64.897)
				)
			)
		)
	)
)
